(kicad_pcb
	(version 20241229)
	(generator "pcbnew")
	(generator_version "9.0")
	(general
		(thickness 1.6642)
		(legacy_teardrops no)
	)
	(paper "A3")
	(title_block
		(title "PolarFire SoM")
		(date "2025-07-22")
		(rev "1.1.4")
		(company "Antmicro Ltd")
		(comment 1 "www.antmicro.com")
		(comment 9 "footprints 466-468 of 470")
	)
	(layers
		(0 "F.Cu" mixed)
		(4 "In1.Cu" power)
		(6 "In2.Cu" signal)
		(8 "In3.Cu" power)
		(10 "In4.Cu" signal)
		(12 "In5.Cu" power)
		(14 "In6.Cu" power)
		(16 "In7.Cu" signal)
		(18 "In8.Cu" power)
		(20 "In9.Cu" signal)
		(22 "In10.Cu" power)
		(24 "In11.Cu" signal)
		(26 "In12.Cu" signal)
		(2 "B.Cu" mixed)
		(9 "F.Adhes" user "F.Adhesive")
		(11 "B.Adhes" user "B.Adhesive")
		(13 "F.Paste" user)
		(15 "B.Paste" user)
		(5 "F.SilkS" user "F.Silkscreen")
		(7 "B.SilkS" user "B.Silkscreen")
		(1 "F.Mask" user)
		(3 "B.Mask" user)
		(17 "Dwgs.User" user "User.Drawings")
		(19 "Cmts.User" user "User.Comments")
		(21 "Eco1.User" user "User.Eco1")
		(23 "Eco2.User" user "User.Eco2")
		(25 "Edge.Cuts" user)
		(27 "Margin" user)
		(31 "F.CrtYd" user "F.Courtyard")
		(29 "B.CrtYd" user "B.Courtyard")
		(35 "F.Fab" user)
		(33 "B.Fab" user)
	)
	(footprint "antmicro-footprints:C_0402_1005Metric"
		(layer "B.Cu")
		(at 219.05 148.27)
		(descr "Capacitor SMD 0402")
		(tags "capacitor SMD 0402")
		(property "Reference" "C113"
			(at 5.84 -8.77 0)
			(layer "B.SilkS")
			(effects
				(font
					(size 0.7 0.7)
					(thickness 0.15)
				)
				(justify right bottom mirror)
			)
		)
		(property "Value" "C_4u7_0402"
			(at -1.022927 -2.155213 0)
			(layer "B.Fab")
			(hide yes)
			(effects
				(font
					(size 0.7 0.7)
					(thickness 0.15)
				)
				(justify right bottom mirror)
			)
		)
		(property "Datasheet" "https://www.murata.com/products/productdetail?partno=GRM155R61A475MEAA%23"
			(at 0 0 0)
			(layer "F.Fab")
			(hide yes)
			(effects
				(font
					(size 1.27 1.27)
					(thickness 0.15)
				)
			)
		)
		(property "Description" "SMD Multilayer Ceramic Capacitor, 4.7 µF, 10 V, 0402 [1005 Metric], ± 20%, X5R, GRM Series"
			(at 0 0 0)
			(layer "F.Fab")
			(hide yes)
			(effects
				(font
					(size 1.27 1.27)
					(thickness 0.15)
				)
			)
		)
		(property "Author" "Antmicro"
			(at 0 0 0)
			(layer "B.Fab")
			(hide yes)
			(effects
				(font
					(size 1 1)
					(thickness 0.15)
				)
				(justify mirror)
			)
		)
		(property "Dielectric" ""
			(at 0 0 0)
			(layer "B.Fab")
			(hide yes)
			(effects
				(font
					(size 1 1)
					(thickness 0.15)
				)
				(justify mirror)
			)
		)
		(property "License" "Apache-2.0"
			(at 0 0 0)
			(layer "B.Fab")
			(hide yes)
			(effects
				(font
					(size 1 1)
					(thickness 0.15)
				)
				(justify mirror)
			)
		)
		(property "MPN" "GRM155R61A475MEAAD"
			(at 0 0 0)
			(layer "B.Fab")
			(hide yes)
			(effects
				(font
					(size 1 1)
					(thickness 0.15)
				)
				(justify mirror)
			)
		)
		(property "Manufacturer" "Murata"
			(at 0 0 0)
			(layer "B.Fab")
			(hide yes)
			(effects
				(font
					(size 1 1)
					(thickness 0.15)
				)
				(justify mirror)
			)
		)
		(property "Public" ""
			(at 0 0 0)
			(layer "B.Fab")
			(hide yes)
			(effects
				(font
					(size 1 1)
					(thickness 0.15)
				)
				(justify mirror)
			)
		)
		(property "Val" "4u7"
			(at 0 0 0)
			(layer "B.Fab")
			(hide yes)
			(effects
				(font
					(size 1 1)
					(thickness 0.15)
				)
				(justify mirror)
			)
		)
		(property "Voltage" ""
			(at 0 0 0)
			(layer "B.Fab")
			(hide yes)
			(effects
				(font
					(size 1 1)
					(thickness 0.15)
				)
				(justify mirror)
			)
		)
		(sheetname "/WiFi_Bluetooth/")
		(sheetfile "wifi_bt.kicad_sch")
		(attr smd)
		(fp_rect
			(start -0.925 0.47)
			(end 0.925 -0.47)
			(stroke
				(width 0.05)
				(type default)
			)
			(fill no)
			(layer "B.CrtYd")
		)
		(fp_line
			(start -0.494 -0.248)
			(end -0.494 0.25)
			(stroke
				(width 0.15)
				(type solid)
			)
			(layer "B.Fab")
		)
		(fp_line
			(start -0.494 0.25)
			(end 0.504 0.25)
			(stroke
				(width 0.15)
				(type solid)
			)
			(layer "B.Fab")
		)
		(fp_line
			(start 0.504 -0.248)
			(end -0.494 -0.248)
			(stroke
				(width 0.15)
				(type solid)
			)
			(layer "B.Fab")
		)
		(fp_line
			(start 0.504 0.25)
			(end 0.504 -0.248)
			(stroke
				(width 0.15)
				(type solid)
			)
			(layer "B.Fab")
		)
		(fp_text user "License: Apache-2.0"
			(at -0.939 -5.799 180)
			(layer "B.Fab")
			(effects
				(font
					(size 0.7 0.7)
					(thickness 0.15)
				)
				(justify left bottom mirror)
			)
		)
		(fp_text user "${REFERENCE}"
			(at -0.939 -4.599 180)
			(layer "B.Fab")
			(effects
				(font
					(size 0.7 0.7)
					(thickness 0.15)
				)
				(justify left bottom mirror)
			)
		)
		(fp_text user "Author: Antmicro"
			(at -0.939 -3.399 180)
			(layer "B.Fab")
			(effects
				(font
					(size 0.7 0.7)
					(thickness 0.15)
				)
				(justify left bottom mirror)
			)
		)
		(pad "1" smd roundrect
			(at -0.48 0)
			(size 0.59 0.64)
			(layers "B.Cu" "B.Mask" "B.Paste")
			(roundrect_rratio 0.25)
			(net 151 "Net-(U26A-VIN_LDO)")
			(pintype "passive")
		)
		(pad "2" smd roundrect
			(at 0.48 0)
			(size 0.59 0.64)
			(layers "B.Cu" "B.Mask" "B.Paste")
			(roundrect_rratio 0.25)
			(net 417 "GND")
			(pintype "passive")
		)
	)
	(footprint "antmicro-footprints:SOT-23-3"
		(layer "B.Cu")
		(at 197.804498 148.636571 45)
		(property "Reference" "Q9"
			(at -1.172331 2.580184 45)
			(layer "B.SilkS")
			(effects
				(font
					(size 0.7 0.7)
					(thickness 0.15)
				)
				(justify right bottom mirror)
			)
		)
		(property "Value" "AO3401A"
			(at -1.9 -2.7 45)
			(layer "B.Fab")
			(hide yes)
			(effects
				(font
					(size 0.7 0.7)
					(thickness 0.15)
				)
				(justify right bottom mirror)
			)
		)
		(property "Datasheet" "http://aosmd.com/res/data_sheets/AO3401A.pdf"
			(at 0 0 45)
			(layer "F.Fab")
			(hide yes)
			(effects
				(font
					(size 1.27 1.27)
					(thickness 0.15)
				)
			)
		)
		(property "Description" "Power MOSFET, P Channel, 30 V, 4 A, 0.07 ohm, SOT-23, Surface Mount"
			(at 0 0 45)
			(layer "F.Fab")
			(hide yes)
			(effects
				(font
					(size 1.27 1.27)
					(thickness 0.15)
				)
			)
		)
		(property "Author" "Antmicro"
			(at 163.037524 -96.334259 0)
			(layer "B.Fab")
			(hide yes)
			(effects
				(font
					(size 1 1)
					(thickness 0.15)
				)
				(justify mirror)
			)
		)
		(property "License" "Apache-2.0"
			(at 163.037524 -96.334259 0)
			(layer "B.Fab")
			(hide yes)
			(effects
				(font
					(size 1 1)
					(thickness 0.15)
				)
				(justify mirror)
			)
		)
		(property "MPN" "AO3401A"
			(at 163.037524 -96.334259 0)
			(layer "B.Fab")
			(hide yes)
			(effects
				(font
					(size 1 1)
					(thickness 0.15)
				)
				(justify mirror)
			)
		)
		(property "Manufacturer" "AOSMD"
			(at 163.037524 -96.334259 0)
			(layer "B.Fab")
			(hide yes)
			(effects
				(font
					(size 1 1)
					(thickness 0.15)
				)
				(justify mirror)
			)
		)
		(sheetname "/Bottom Connector/")
		(sheetfile "bottom-connector.kicad_sch")
		(attr smd)
		(fp_line
			(start -0.7 -1.5)
			(end -0.7 -1.35)
			(stroke
				(width 0.15)
				(type solid)
			)
			(layer "B.SilkS")
		)
		(fp_line
			(start 0.7 -1.5)
			(end -0.7 -1.5)
			(stroke
				(width 0.15)
				(type solid)
			)
			(layer "B.SilkS")
		)
		(fp_line
			(start -1.45 1.35)
			(end -0.85 1.35)
			(stroke
				(width 0.15)
				(type solid)
			)
			(layer "B.SilkS")
		)
		(fp_line
			(start 0.7 -0.4)
			(end 0.7 -1.5)
			(stroke
				(width 0.15)
				(type solid)
			)
			(layer "B.SilkS")
		)
		(fp_line
			(start -0.85 1.35)
			(end -0.7 1.5)
			(stroke
				(width 0.15)
				(type solid)
			)
			(layer "B.SilkS")
		)
		(fp_line
			(start 0.7 0.4)
			(end 0.7 1.5)
			(stroke
				(width 0.15)
				(type solid)
			)
			(layer "B.SilkS")
		)
		(fp_line
			(start 0.7 1.5)
			(end -0.7 1.5)
			(stroke
				(width 0.15)
				(type solid)
			)
			(layer "B.SilkS")
		)
		(fp_line
			(start -1.749999 -1.4)
			(end -1.749999 -0.5)
			(stroke
				(width 0.05)
				(type solid)
			)
			(layer "B.CrtYd")
		)
		(fp_line
			(start -0.85 -1.65)
			(end -0.85 -1.4)
			(stroke
				(width 0.05)
				(type solid)
			)
			(layer "B.CrtYd")
		)
		(fp_line
			(start -0.85 -1.4)
			(end -1.749999 -1.4)
			(stroke
				(width 0.05)
				(type solid)
			)
			(layer "B.CrtYd")
		)
		(fp_line
			(start -1.749999 -0.5)
			(end -0.85 -0.5)
			(stroke
				(width 0.05)
				(type solid)
			)
			(layer "B.CrtYd")
		)
		(fp_line
			(start -0.85 -0.5)
			(end -0.85 0.5)
			(stroke
				(width 0.05)
				(type solid)
			)
			(layer "B.CrtYd")
		)
		(fp_line
			(start -1.749999 0.5)
			(end -1.749999 1.4)
			(stroke
				(width 0.05)
				(type solid)
			)
			(layer "B.CrtYd")
		)
		(fp_line
			(start 0.85 -1.65)
			(end -0.85 -1.65)
			(stroke
				(width 0.05)
				(type solid)
			)
			(layer "B.CrtYd")
		)
		(fp_line
			(start -0.85 0.5)
			(end -1.749999 0.5)
			(stroke
				(width 0.05)
				(type solid)
			)
			(layer "B.CrtYd")
		)
		(fp_line
			(start 0.85 -0.45)
			(end 0.85 -1.65)
			(stroke
				(width 0.05)
				(type solid)
			)
			(layer "B.CrtYd")
		)
		(fp_line
			(start -0.900001 1.4)
			(end -1.749999 1.4)
			(stroke
				(width 0.05)
				(type solid)
			)
			(layer "B.CrtYd")
		)
		(fp_line
			(start -0.9 1.6)
			(end -0.900001 1.4)
			(stroke
				(width 0.05)
				(type solid)
			)
			(layer "B.CrtYd")
		)
		(fp_line
			(start -0.9 1.6)
			(end 0.825 1.6)
			(stroke
				(width 0.05)
				(type solid)
			)
			(layer "B.CrtYd")
		)
		(fp_line
			(start 0.825 0.45)
			(end 1.75 0.45)
			(stroke
				(width 0.05)
				(type solid)
			)
			(layer "B.CrtYd")
		)
		(fp_line
			(start 1.75 -0.45)
			(end 0.85 -0.45)
			(stroke
				(width 0.05)
				(type solid)
			)
			(layer "B.CrtYd")
		)
		(fp_line
			(start 1.75 0.45)
			(end 1.75 -0.45)
			(stroke
				(width 0.05)
				(type solid)
			)
			(layer "B.CrtYd")
		)
		(fp_line
			(start 0.825 1.6)
			(end 0.825 0.45)
			(stroke
				(width 0.05)
				(type solid)
			)
			(layer "B.CrtYd")
		)
		(fp_line
			(start -0.712 -1.519)
			(end 0.688 -1.519)
			(stroke
				(width 0.15)
				(type solid)
			)
			(layer "B.Fab")
		)
		(fp_line
			(start 0.688 -1.519)
			(end 0.688 1.52)
			(stroke
				(width 0.15)
				(type solid)
			)
			(layer "B.Fab")
		)
		(fp_line
			(start -0.712001 1.325)
			(end -0.712 -1.523001)
			(stroke
				(width 0.15)
				(type solid)
			)
			(layer "B.Fab")
		)
		(fp_line
			(start -0.437 1.526)
			(end -0.712001 1.325)
			(stroke
				(width 0.15)
				(type solid)
			)
			(layer "B.Fab")
		)
		(fp_line
			(start -0.437 1.526)
			(end 0.688 1.525999)
			(stroke
				(width 0.15)
				(type solid)
			)
			(layer "B.Fab")
		)
		(fp_text user "${REFERENCE}"
			(at -1.837 -4 225)
			(layer "B.Fab")
			(effects
				(font
					(size 0.7 0.7)
					(thickness 0.15)
				)
				(justify left bottom mirror)
			)
		)
		(fp_text user "License: Apache-2.0"
			(at -1.8 -6.8 225)
			(layer "B.Fab")
			(effects
				(font
					(size 0.7 0.7)
					(thickness 0.15)
				)
				(justify left bottom mirror)
			)
		)
		(fp_text user "Author: Antmicro"
			(at -1.837 -5.3 225)
			(layer "B.Fab")
			(effects
				(font
					(size 0.7 0.7)
					(thickness 0.15)
				)
				(justify left bottom mirror)
			)
		)
		(pad "1" smd roundrect
			(at -1.1 0.951 45)
			(size 1 0.6)
			(layers "B.Cu" "B.Mask" "B.Paste")
			(roundrect_rratio 0.15)
			(net 411 "Net-(Q3-BIAS)")
			(pinfunction "G")
			(pintype "input")
		)
		(pad "2" smd roundrect
			(at -1.1 -0.949 45)
			(size 1 0.6)
			(layers "B.Cu" "B.Mask" "B.Paste")
			(roundrect_rratio 0.15)
			(net 90 "+5V")
			(pinfunction "S")
			(pintype "passive")
		)
		(pad "3" smd roundrect
			(at 1.1 0.0005 45)
			(size 1 0.6)
			(layers "B.Cu" "B.Mask" "B.Paste")
			(roundrect_rratio 0.15)
			(net 410 "Net-(Q3-D)")
			(pinfunction "D")
			(pintype "passive")
		)
	)
	(footprint "antmicro-footprints:C_0402_1005Metric"
		(layer "B.Cu")
		(at 194.41 130.616)
		(descr "Capacitor SMD 0402")
		(tags "capacitor SMD 0402")
		(property "Reference" "C30"
			(at -0.81 0.434 180)
			(layer "B.SilkS")
			(effects
				(font
					(size 0.7 0.7)
					(thickness 0.15)
				)
				(justify left bottom mirror)
			)
		)
		(property "Value" "C_1n_0402"
			(at -1.022927 -2.155213 180)
			(layer "B.Fab")
			(hide yes)
			(effects
				(font
					(size 0.7 0.7)
					(thickness 0.15)
				)
				(justify left bottom mirror)
			)
		)
		(property "Datasheet" "https://www.murata.com/products/productdetail?partno=GRM1555C1H102JA01%23"
			(at 0 0 0)
			(layer "F.Fab")
			(hide yes)
			(effects
				(font
					(size 1.27 1.27)
					(thickness 0.15)
				)
			)
		)
		(property "Description" "SMD Multilayer Ceramic Capacitor, 1000 pF, 50 V, 0402 [1005 Metric], ± 5%, C0G / NP0, GRM Series"
			(at 0 0 0)
			(layer "F.Fab")
			(hide yes)
			(effects
				(font
					(size 1.27 1.27)
					(thickness 0.15)
				)
			)
		)
		(property "Author" "Antmicro"
			(at 0 0 0)
			(layer "B.Fab")
			(hide yes)
			(effects
				(font
					(size 1 1)
					(thickness 0.15)
				)
				(justify mirror)
			)
		)
		(property "Dielectric" "C0G"
			(at 0 0 0)
			(layer "B.Fab")
			(hide yes)
			(effects
				(font
					(size 1 1)
					(thickness 0.15)
				)
				(justify mirror)
			)
		)
		(property "License" "Apache-2.0"
			(at 0 0 0)
			(layer "B.Fab")
			(hide yes)
			(effects
				(font
					(size 1 1)
					(thickness 0.15)
				)
				(justify mirror)
			)
		)
		(property "MPN" "GRM1555C1H102JA01D"
			(at 0 0 0)
			(layer "B.Fab")
			(hide yes)
			(effects
				(font
					(size 1 1)
					(thickness 0.15)
				)
				(justify mirror)
			)
		)
		(property "Manufacturer" "Murata"
			(at 0 0 0)
			(layer "B.Fab")
			(hide yes)
			(effects
				(font
					(size 1 1)
					(thickness 0.15)
				)
				(justify mirror)
			)
		)
		(property "Public" ""
			(at 0 0 0)
			(layer "B.Fab")
			(hide yes)
			(effects
				(font
					(size 1 1)
					(thickness 0.15)
				)
				(justify mirror)
			)
		)
		(property "Val" "1n"
			(at 0 0 0)
			(layer "B.Fab")
			(hide yes)
			(effects
				(font
					(size 1 1)
					(thickness 0.15)
				)
				(justify mirror)
			)
		)
		(property "Voltage" "50V"
			(at 0 0 0)
			(layer "B.Fab")
			(hide yes)
			(effects
				(font
					(size 1 1)
					(thickness 0.15)
				)
				(justify mirror)
			)
		)
		(sheetname "/FPGA Supply/")
		(sheetfile "fpga-supply.kicad_sch")
		(attr smd)
		(fp_rect
			(start -0.925 0.47)
			(end 0.925 -0.47)
			(stroke
				(width 0.05)
				(type default)
			)
			(fill no)
			(layer "B.CrtYd")
		)
		(fp_line
			(start -0.494 -0.248)
			(end -0.494 0.25)
			(stroke
				(width 0.15)
				(type solid)
			)
			(layer "B.Fab")
		)
		(fp_line
			(start -0.494 0.25)
			(end 0.504 0.25)
			(stroke
				(width 0.15)
				(type solid)
			)
			(layer "B.Fab")
		)
		(fp_line
			(start 0.504 -0.248)
			(end -0.494 -0.248)
			(stroke
				(width 0.15)
				(type solid)
			)
			(layer "B.Fab")
		)
		(fp_line
			(start 0.504 0.25)
			(end 0.504 -0.248)
			(stroke
				(width 0.15)
				(type solid)
			)
			(layer "B.Fab")
		)
		(fp_text user "Author: Antmicro"
			(at -0.939 -3.399 180)
			(layer "B.Fab")
			(effects
				(font
					(size 0.7 0.7)
					(thickness 0.15)
				)
				(justify left bottom mirror)
			)
		)
		(fp_text user "${REFERENCE}"
			(at -0.939 -4.599 180)
			(layer "B.Fab")
			(effects
				(font
					(size 0.7 0.7)
					(thickness 0.15)
				)
				(justify left bottom mirror)
			)
		)
		(fp_text user "License: Apache-2.0"
			(at -0.939 -5.799 180)
			(layer "B.Fab")
			(effects
				(font
					(size 0.7 0.7)
					(thickness 0.15)
				)
				(justify left bottom mirror)
			)
		)
		(pad "1" smd roundrect
			(at -0.48 0)
			(size 0.59 0.64)
			(layers "B.Cu" "B.Mask" "B.Paste")
			(roundrect_rratio 0.25)
			(net 417 "GND")
			(pintype "passive")
		)
		(pad "2" smd roundrect
			(at 0.48 0)
			(size 0.59 0.64)
			(layers "B.Cu" "B.Mask" "B.Paste")
			(roundrect_rratio 0.25)
			(net 418 "+2V5")
			(pintype "passive")
		)
	)
)
